# S9S_MB_2U (Grand Teton) — schematic netlist excerpt (pin names and nets, part order shuffled) for the footprints in the layout excerpt that follows; sources: Cadence DE-HDL packaged netlist, KiCad conversion of 03242023_DA0F0TMBIJ0_F0T_Motherboard_J_brd_V01_OCP.brd

R4658  Q_RES  1K 1% EMPTY  pkg 0402LF  page 167 : A = FM_P2E_BUF2_VOD_SEL ; B = GND
R1014  Q_RES  0 5% CHIP  pkg 0402LF  page 209 : A = CLK_25M_CK440_CPU0_DN ; B = CLK_25M_CK440_CPU0_R_DN

(kicad_pcb
	(version 20260206)
	(generator "pcbnew")
	(generator_version "10.0")
	(general
		(thickness 1.6)
		(legacy_teardrops no)
	)
	(paper "A4")
	(title_block
		(title "03242023_DA0F0TMBIJ0_F0T_Motherboard_J_brd_V01_OCP.brd")
		(comment 1 "Grand Teton / footprints 144-145 of 6105")
	)
	(layers
		(0 "F.Cu" signal "TOP")
		(4 "In1.Cu" signal "GND")
		(6 "In2.Cu" signal "IN1")
		(8 "In3.Cu" signal "GND1")
		(10 "In4.Cu" signal "IN2")
		(12 "In5.Cu" signal "GND2")
		(14 "In6.Cu" signal "IN3")
		(16 "In7.Cu" signal "GND3")
		(18 "In8.Cu" signal "VCC")
		(20 "In9.Cu" signal "VCC1")
		(22 "In10.Cu" signal "GND4")
		(24 "In11.Cu" signal "IN4")
		(26 "In12.Cu" signal "GND5")
		(28 "In13.Cu" signal "IN5")
		(30 "In14.Cu" signal "GND6")
		(32 "In15.Cu" signal "IN6")
		(34 "In16.Cu" signal "GND7")
		(2 "B.Cu" signal "BOTTOM")
		(9 "F.Adhes" user "F.Adhesive")
		(11 "B.Adhes" user "B.Adhesive")
		(13 "F.Paste" user "Package Geometry/Pastemask Top")
		(15 "B.Paste" user "Package Geometry/Pastemask Bottom")
		(5 "F.SilkS" user "Ref Des/Silkscreen Top")
		(7 "B.SilkS" user "Ref Des/Silkscreen Bottom")
		(1 "F.Mask" user "Board Geometry/Soldermask Top")
		(3 "B.Mask" user "Board Geometry/Soldermask Bottom")
		(17 "Dwgs.User" user "User.Drawings")
		(19 "Cmts.User" user "User.Comments")
		(21 "Eco1.User" user "User.Eco1")
		(23 "Eco2.User" user "User.Eco2")
		(25 "Edge.Cuts" user "Board Geometry/Outline")
		(27 "Margin" user)
		(31 "F.CrtYd" user "Package Geometry/Place Bound Top")
		(29 "B.CrtYd" user "Package Geometry/Place Bound Bottom")
		(35 "F.Fab" user "Ref Des/Assembly Top")
		(33 "B.Fab" user "Ref Des/Assembly Bottom")
	)
	(footprint ""
		(layer "F.Cu")
		(at 241.295428 -108.743496 180)
		(property "Reference" "R1014"
			(at 0 0 180)
			(layer "F.SilkS")
			(hide yes)
			(effects
				(font
					(size 1.27 1.27)
				)
			)
		)
		(property "Value" ""
			(at 0 0 180)
			(layer "F.Fab")
			(effects
				(font
					(size 1.27 1.27)
				)
			)
		)
		(duplicate_pad_numbers_are_jumpers no)
		(fp_line
			(start 0.7874 0.4064)
			(end -0.7874 0.4064)
			(stroke
				(width 0.1524)
				(type default)
			)
			(layer "F.SilkS")
		)
		(fp_line
			(start 0.7874 -0.4064)
			(end 0.7874 0.4064)
			(stroke
				(width 0.1524)
				(type default)
			)
			(layer "F.SilkS")
		)
		(fp_line
			(start -0.7874 0.4064)
			(end -0.7874 -0.4064)
			(stroke
				(width 0.1524)
				(type default)
			)
			(layer "F.SilkS")
		)
		(fp_line
			(start -0.7874 -0.4064)
			(end 0.7874 -0.4064)
			(stroke
				(width 0.1524)
				(type default)
			)
			(layer "F.SilkS")
		)
		(fp_line
			(start 0.67945 0.3048)
			(end 0.120396 0.3048)
			(stroke
				(width 0.1)
				(type default)
			)
			(layer "F.Fab")
		)
		(fp_line
			(start 0.67945 -0.3048)
			(end 0.67945 0.3048)
			(stroke
				(width 0.1)
				(type default)
			)
			(layer "F.Fab")
		)
		(fp_line
			(start 0.12065 -0.2794)
			(end 0.12065 -0.3048)
			(stroke
				(width 0.1)
				(type default)
			)
			(layer "F.Fab")
		)
		(fp_line
			(start 0.12065 -0.3048)
			(end 0.67945 -0.3048)
			(stroke
				(width 0.1)
				(type default)
			)
			(layer "F.Fab")
		)
		(fp_line
			(start 0.120396 0.3048)
			(end 0.120396 0.2794)
			(stroke
				(width 0.1)
				(type default)
			)
			(layer "F.Fab")
		)
		(fp_line
			(start 0.120396 0.2794)
			(end -0.12065 0.2794)
			(stroke
				(width 0.1)
				(type default)
			)
			(layer "F.Fab")
		)
		(fp_line
			(start -0.12065 0.3048)
			(end -0.67945 0.3048)
			(stroke
				(width 0.1)
				(type default)
			)
			(layer "F.Fab")
		)
		(fp_line
			(start -0.12065 0.2794)
			(end -0.12065 0.3048)
			(stroke
				(width 0.1)
				(type default)
			)
			(layer "F.Fab")
		)
		(fp_line
			(start -0.12065 -0.2794)
			(end 0.12065 -0.2794)
			(stroke
				(width 0.1)
				(type default)
			)
			(layer "F.Fab")
		)
		(fp_line
			(start -0.12065 -0.305054)
			(end -0.12065 -0.2794)
			(stroke
				(width 0.1)
				(type default)
			)
			(layer "F.Fab")
		)
		(fp_line
			(start -0.67945 0.3048)
			(end -0.67945 -0.305054)
			(stroke
				(width 0.1)
				(type default)
			)
			(layer "F.Fab")
		)
		(fp_line
			(start -0.67945 -0.305054)
			(end -0.12065 -0.305054)
			(stroke
				(width 0.1)
				(type default)
			)
			(layer "F.Fab")
		)
		(pad "1" smd circle
			(at -0.40005 0 180)
			(size 0 0)
			(layers "F.Cu" "F.Mask" "F.Paste")
			(net "CLK_25M_CK440_CPU0_DN")
		)
		(pad "2" smd circle
			(at 0.40005 0 180)
			(size 0 0)
			(layers "F.Cu" "F.Mask" "F.Paste")
			(net "CLK_25M_CK440_CPU0_R_DN")
		)
	)
	(footprint ""
		(layer "F.Cu")
		(at 33.449006 -391.635996 180)
		(property "Reference" "R4658"
			(at 0 0 180)
			(layer "F.SilkS")
			(hide yes)
			(effects
				(font
					(size 1.27 1.27)
				)
			)
		)
		(property "Value" ""
			(at 0 0 180)
			(layer "F.Fab")
			(effects
				(font
					(size 1.27 1.27)
				)
			)
		)
		(duplicate_pad_numbers_are_jumpers no)
		(fp_line
			(start 0.7874 0.4064)
			(end -0.7874 0.4064)
			(stroke
				(width 0.1524)
				(type default)
			)
			(layer "F.SilkS")
		)
		(fp_line
			(start 0.7874 -0.4064)
			(end 0.7874 0.4064)
			(stroke
				(width 0.1524)
				(type default)
			)
			(layer "F.SilkS")
		)
		(fp_line
			(start -0.7874 0.4064)
			(end -0.7874 -0.4064)
			(stroke
				(width 0.1524)
				(type default)
			)
			(layer "F.SilkS")
		)
		(fp_line
			(start -0.7874 -0.4064)
			(end 0.7874 -0.4064)
			(stroke
				(width 0.1524)
				(type default)
			)
			(layer "F.SilkS")
		)
		(fp_line
			(start 0.67945 0.3048)
			(end 0.120396 0.3048)
			(stroke
				(width 0.1)
				(type default)
			)
			(layer "F.Fab")
		)
		(fp_line
			(start 0.67945 -0.3048)
			(end 0.67945 0.3048)
			(stroke
				(width 0.1)
				(type default)
			)
			(layer "F.Fab")
		)
		(fp_line
			(start 0.12065 -0.2794)
			(end 0.12065 -0.3048)
			(stroke
				(width 0.1)
				(type default)
			)
			(layer "F.Fab")
		)
		(fp_line
			(start 0.12065 -0.3048)
			(end 0.67945 -0.3048)
			(stroke
				(width 0.1)
				(type default)
			)
			(layer "F.Fab")
		)
		(fp_line
			(start 0.120396 0.3048)
			(end 0.120396 0.2794)
			(stroke
				(width 0.1)
				(type default)
			)
			(layer "F.Fab")
		)
		(fp_line
			(start 0.120396 0.2794)
			(end -0.12065 0.2794)
			(stroke
				(width 0.1)
				(type default)
			)
			(layer "F.Fab")
		)
		(fp_line
			(start -0.12065 0.3048)
			(end -0.67945 0.3048)
			(stroke
				(width 0.1)
				(type default)
			)
			(layer "F.Fab")
		)
		(fp_line
			(start -0.12065 0.2794)
			(end -0.12065 0.3048)
			(stroke
				(width 0.1)
				(type default)
			)
			(layer "F.Fab")
		)
		(fp_line
			(start -0.12065 -0.2794)
			(end 0.12065 -0.2794)
			(stroke
				(width 0.1)
				(type default)
			)
			(layer "F.Fab")
		)
		(fp_line
			(start -0.12065 -0.305054)
			(end -0.12065 -0.2794)
			(stroke
				(width 0.1)
				(type default)
			)
			(layer "F.Fab")
		)
		(fp_line
			(start -0.67945 0.3048)
			(end -0.67945 -0.305054)
			(stroke
				(width 0.1)
				(type default)
			)
			(layer "F.Fab")
		)
		(fp_line
			(start -0.67945 -0.305054)
			(end -0.12065 -0.305054)
			(stroke
				(width 0.1)
				(type default)
			)
			(layer "F.Fab")
		)
		(pad "1" smd circle
			(at -0.40005 0 180)
			(size 0 0)
			(layers "F.Cu" "F.Mask" "F.Paste")
			(net "FM_P2E_BUF2_VOD_SEL")
		)
		(pad "2" smd circle
			(at 0.40005 0 180)
			(size 0 0)
			(layers "F.Cu" "F.Mask" "F.Paste")
			(net "GND")
		)
	)
)
